(kicad_pcb
	(version 20260206)
	(generator "pcbnew")
	(generator_version "10.0")
	(general
		(thickness 1.6)
		(legacy_teardrops no)
	)
	(paper "A4")
	(title_block
		(title "01162023_DA0F0TEBIF0_F0T_Expander_BD_F_brd_V02_OCP.brd")
		(comment 1 "Grand Teton / footprints 5698-5703 of 9728")
	)
	(layers
		(0 "F.Cu" signal "TOP")
		(4 "In1.Cu" signal "GND")
		(6 "In2.Cu" signal "VCC")
		(8 "In3.Cu" signal "VCC1")
		(10 "In4.Cu" signal "GND1")
		(12 "In5.Cu" signal "IN1")
		(14 "In6.Cu" signal "GND2")
		(16 "In7.Cu" signal "IN2")
		(18 "In8.Cu" signal "GND3")
		(20 "In9.Cu" signal "IN3")
		(22 "In10.Cu" signal "GND4")
		(24 "In11.Cu" signal "IN4")
		(26 "In12.Cu" signal "GND5")
		(28 "In13.Cu" signal "IN5")
		(30 "In14.Cu" signal "GND6")
		(32 "In15.Cu" signal "IN6")
		(34 "In16.Cu" signal "GND7")
		(2 "B.Cu" signal "BOTTOM")
		(9 "F.Adhes" user "F.Adhesive")
		(11 "B.Adhes" user "B.Adhesive")
		(13 "F.Paste" user "Package Geometry/Pastemask Top")
		(15 "B.Paste" user "Package Geometry/Pastemask Bottom")
		(5 "F.SilkS" user "Ref Des/Silkscreen Top")
		(7 "B.SilkS" user "Ref Des/Silkscreen Bottom")
		(1 "F.Mask" user "Board Geometry/Soldermask Top")
		(3 "B.Mask" user "Board Geometry/Soldermask Bottom")
		(17 "Dwgs.User" user "User.Drawings")
		(19 "Cmts.User" user "User.Comments")
		(21 "Eco1.User" user "User.Eco1")
		(23 "Eco2.User" user "User.Eco2")
		(25 "Edge.Cuts" user "Board Geometry/Outline")
		(27 "Margin" user)
		(31 "F.CrtYd" user "Package Geometry/Place Bound Top")
		(29 "B.CrtYd" user "Package Geometry/Place Bound Bottom")
		(35 "F.Fab" user "Ref Des/Assembly Top")
		(33 "B.Fab" user "Ref Des/Assembly Bottom")
	)
	(footprint ""
		(layer "F.Cu")
		(at 424.415458 -42.853102 180)
		(property "Reference" "R5906"
			(at 0 0 180)
			(layer "F.SilkS")
			(hide yes)
			(effects
				(font
					(size 1.27 1.27)
				)
			)
		)
		(property "Value" ""
			(at 0 0 180)
			(layer "F.Fab")
			(effects
				(font
					(size 1.27 1.27)
				)
			)
		)
		(duplicate_pad_numbers_are_jumpers no)
		(fp_line
			(start 0.7874 0.4064)
			(end -0.7874 0.4064)
			(stroke
				(width 0.1524)
				(type default)
			)
			(layer "F.SilkS")
		)
		(fp_line
			(start 0.7874 -0.4064)
			(end 0.7874 0.4064)
			(stroke
				(width 0.1524)
				(type default)
			)
			(layer "F.SilkS")
		)
		(fp_line
			(start -0.7874 0.4064)
			(end -0.7874 -0.4064)
			(stroke
				(width 0.1524)
				(type default)
			)
			(layer "F.SilkS")
		)
		(fp_line
			(start -0.7874 -0.4064)
			(end 0.7874 -0.4064)
			(stroke
				(width 0.1524)
				(type default)
			)
			(layer "F.SilkS")
		)
		(fp_line
			(start 0.67945 0.3048)
			(end 0.120396 0.3048)
			(stroke
				(width 0.1)
				(type default)
			)
			(layer "F.Fab")
		)
		(fp_line
			(start 0.67945 -0.3048)
			(end 0.67945 0.3048)
			(stroke
				(width 0.1)
				(type default)
			)
			(layer "F.Fab")
		)
		(fp_line
			(start 0.12065 -0.2794)
			(end 0.12065 -0.3048)
			(stroke
				(width 0.1)
				(type default)
			)
			(layer "F.Fab")
		)
		(fp_line
			(start 0.12065 -0.3048)
			(end 0.67945 -0.3048)
			(stroke
				(width 0.1)
				(type default)
			)
			(layer "F.Fab")
		)
		(fp_line
			(start 0.120396 0.3048)
			(end 0.120396 0.2794)
			(stroke
				(width 0.1)
				(type default)
			)
			(layer "F.Fab")
		)
		(fp_line
			(start 0.120396 0.2794)
			(end -0.12065 0.2794)
			(stroke
				(width 0.1)
				(type default)
			)
			(layer "F.Fab")
		)
		(fp_line
			(start -0.12065 0.3048)
			(end -0.67945 0.3048)
			(stroke
				(width 0.1)
				(type default)
			)
			(layer "F.Fab")
		)
		(fp_line
			(start -0.12065 0.2794)
			(end -0.12065 0.3048)
			(stroke
				(width 0.1)
				(type default)
			)
			(layer "F.Fab")
		)
		(fp_line
			(start -0.12065 -0.2794)
			(end 0.12065 -0.2794)
			(stroke
				(width 0.1)
				(type default)
			)
			(layer "F.Fab")
		)
		(fp_line
			(start -0.12065 -0.305054)
			(end -0.12065 -0.2794)
			(stroke
				(width 0.1)
				(type default)
			)
			(layer "F.Fab")
		)
		(fp_line
			(start -0.67945 0.3048)
			(end -0.67945 -0.305054)
			(stroke
				(width 0.1)
				(type default)
			)
			(layer "F.Fab")
		)
		(fp_line
			(start -0.67945 -0.305054)
			(end -0.12065 -0.305054)
			(stroke
				(width 0.1)
				(type default)
			)
			(layer "F.Fab")
		)
		(pad "1" smd circle
			(at -0.40005 0 180)
			(size 0 0)
			(layers "F.Cu" "F.Mask" "F.Paste")
			(net "SSD14_ADC_A1")
		)
		(pad "2" smd circle
			(at 0.40005 0 180)
			(size 0 0)
			(layers "F.Cu" "F.Mask" "F.Paste")
			(net "SMB_SSD14_ADC_SCL")
		)
	)
	(footprint ""
		(layer "F.Cu")
		(at 14.689836 -255.046734 -90)
		(property "Reference" "R6473"
			(at 0 0 270)
			(layer "F.SilkS")
			(hide yes)
			(effects
				(font
					(size 1.27 1.27)
				)
			)
		)
		(property "Value" ""
			(at 0 0 270)
			(layer "F.Fab")
			(effects
				(font
					(size 1.27 1.27)
				)
			)
		)
		(duplicate_pad_numbers_are_jumpers no)
		(fp_line
			(start -0.7874 0.4064)
			(end -0.7874 -0.4064)
			(stroke
				(width 0.1524)
				(type default)
			)
			(layer "F.SilkS")
		)
		(fp_line
			(start 0.7874 0.4064)
			(end -0.7874 0.4064)
			(stroke
				(width 0.1524)
				(type default)
			)
			(layer "F.SilkS")
		)
		(fp_line
			(start -0.7874 -0.4064)
			(end 0.7874 -0.4064)
			(stroke
				(width 0.1524)
				(type default)
			)
			(layer "F.SilkS")
		)
		(fp_line
			(start 0.7874 -0.4064)
			(end 0.7874 0.4064)
			(stroke
				(width 0.1524)
				(type default)
			)
			(layer "F.SilkS")
		)
		(fp_line
			(start -0.67945 0.3048)
			(end -0.67945 -0.305054)
			(stroke
				(width 0.1)
				(type default)
			)
			(layer "F.Fab")
		)
		(fp_line
			(start -0.12065 0.3048)
			(end -0.67945 0.3048)
			(stroke
				(width 0.1)
				(type default)
			)
			(layer "F.Fab")
		)
		(fp_line
			(start 0.120396 0.3048)
			(end 0.120396 0.2794)
			(stroke
				(width 0.1)
				(type default)
			)
			(layer "F.Fab")
		)
		(fp_line
			(start 0.67945 0.3048)
			(end 0.120396 0.3048)
			(stroke
				(width 0.1)
				(type default)
			)
			(layer "F.Fab")
		)
		(fp_line
			(start -0.12065 0.2794)
			(end -0.12065 0.3048)
			(stroke
				(width 0.1)
				(type default)
			)
			(layer "F.Fab")
		)
		(fp_line
			(start 0.120396 0.2794)
			(end -0.12065 0.2794)
			(stroke
				(width 0.1)
				(type default)
			)
			(layer "F.Fab")
		)
		(fp_line
			(start -0.12065 -0.2794)
			(end 0.12065 -0.2794)
			(stroke
				(width 0.1)
				(type default)
			)
			(layer "F.Fab")
		)
		(fp_line
			(start 0.12065 -0.2794)
			(end 0.12065 -0.3048)
			(stroke
				(width 0.1)
				(type default)
			)
			(layer "F.Fab")
		)
		(fp_line
			(start 0.12065 -0.3048)
			(end 0.67945 -0.3048)
			(stroke
				(width 0.1)
				(type default)
			)
			(layer "F.Fab")
		)
		(fp_line
			(start 0.67945 -0.3048)
			(end 0.67945 0.3048)
			(stroke
				(width 0.1)
				(type default)
			)
			(layer "F.Fab")
		)
		(fp_line
			(start -0.67945 -0.305054)
			(end -0.12065 -0.305054)
			(stroke
				(width 0.1)
				(type default)
			)
			(layer "F.Fab")
		)
		(fp_line
			(start -0.12065 -0.305054)
			(end -0.12065 -0.2794)
			(stroke
				(width 0.1)
				(type default)
			)
			(layer "F.Fab")
		)
		(pad "1" smd circle
			(at -0.40005 0 270)
			(size 0 0)
			(layers "F.Cu" "F.Mask" "F.Paste")
			(net "P1V25_SERDES_VDDPLL_PEX0")
		)
		(pad "2" smd circle
			(at 0.40005 0 270)
			(size 0 0)
			(layers "F.Cu" "F.Mask" "F.Paste")
			(net "P1V25_SERDES_VDDPLL_PEX0_C10")
		)
	)
	(footprint ""
		(layer "F.Cu")
		(at 8.049768 -159.844994 180)
		(property "Reference" "PR6870"
			(at 0 0 180)
			(layer "F.SilkS")
			(hide yes)
			(effects
				(font
					(size 1.27 1.27)
				)
			)
		)
		(property "Value" ""
			(at 0 0 180)
			(layer "F.Fab")
			(effects
				(font
					(size 1.27 1.27)
				)
			)
		)
		(duplicate_pad_numbers_are_jumpers no)
		(fp_line
			(start 0.7874 0.4064)
			(end -0.7874 0.4064)
			(stroke
				(width 0.1524)
				(type default)
			)
			(layer "F.SilkS")
		)
		(fp_line
			(start 0.7874 -0.4064)
			(end 0.7874 0.4064)
			(stroke
				(width 0.1524)
				(type default)
			)
			(layer "F.SilkS")
		)
		(fp_line
			(start -0.7874 0.4064)
			(end -0.7874 -0.4064)
			(stroke
				(width 0.1524)
				(type default)
			)
			(layer "F.SilkS")
		)
		(fp_line
			(start -0.7874 -0.4064)
			(end 0.7874 -0.4064)
			(stroke
				(width 0.1524)
				(type default)
			)
			(layer "F.SilkS")
		)
		(fp_line
			(start 0.67945 0.3048)
			(end 0.120396 0.3048)
			(stroke
				(width 0.1)
				(type default)
			)
			(layer "F.Fab")
		)
		(fp_line
			(start 0.67945 -0.3048)
			(end 0.67945 0.3048)
			(stroke
				(width 0.1)
				(type default)
			)
			(layer "F.Fab")
		)
		(fp_line
			(start 0.12065 -0.2794)
			(end 0.12065 -0.3048)
			(stroke
				(width 0.1)
				(type default)
			)
			(layer "F.Fab")
		)
		(fp_line
			(start 0.12065 -0.3048)
			(end 0.67945 -0.3048)
			(stroke
				(width 0.1)
				(type default)
			)
			(layer "F.Fab")
		)
		(fp_line
			(start 0.120396 0.3048)
			(end 0.120396 0.2794)
			(stroke
				(width 0.1)
				(type default)
			)
			(layer "F.Fab")
		)
		(fp_line
			(start 0.120396 0.2794)
			(end -0.12065 0.2794)
			(stroke
				(width 0.1)
				(type default)
			)
			(layer "F.Fab")
		)
		(fp_line
			(start -0.12065 0.3048)
			(end -0.67945 0.3048)
			(stroke
				(width 0.1)
				(type default)
			)
			(layer "F.Fab")
		)
		(fp_line
			(start -0.12065 0.2794)
			(end -0.12065 0.3048)
			(stroke
				(width 0.1)
				(type default)
			)
			(layer "F.Fab")
		)
		(fp_line
			(start -0.12065 -0.2794)
			(end 0.12065 -0.2794)
			(stroke
				(width 0.1)
				(type default)
			)
			(layer "F.Fab")
		)
		(fp_line
			(start -0.12065 -0.305054)
			(end -0.12065 -0.2794)
			(stroke
				(width 0.1)
				(type default)
			)
			(layer "F.Fab")
		)
		(fp_line
			(start -0.67945 0.3048)
			(end -0.67945 -0.305054)
			(stroke
				(width 0.1)
				(type default)
			)
			(layer "F.Fab")
		)
		(fp_line
			(start -0.67945 -0.305054)
			(end -0.12065 -0.305054)
			(stroke
				(width 0.1)
				(type default)
			)
			(layer "F.Fab")
		)
		(pad "1" smd circle
			(at -0.40005 0 180)
			(size 0 0)
			(layers "F.Cu" "F.Mask" "F.Paste")
			(net "P12V_NIC0_CO_FLTB")
		)
		(pad "2" smd circle
			(at 0.40005 0 180)
			(size 0 0)
			(layers "F.Cu" "F.Mask" "F.Paste")
			(net "P3V3_AUX")
		)
	)
	(footprint ""
		(layer "F.Cu")
		(at 374.543828 -44.87291)
		(property "Reference" "R639"
			(at 0 0 0)
			(layer "F.SilkS")
			(hide yes)
			(effects
				(font
					(size 1.27 1.27)
				)
			)
		)
		(property "Value" ""
			(at 0 0 0)
			(layer "F.Fab")
			(effects
				(font
					(size 1.27 1.27)
				)
			)
		)
		(duplicate_pad_numbers_are_jumpers no)
		(fp_line
			(start -0.7874 -0.4064)
			(end 0.7874 -0.4064)
			(stroke
				(width 0.1524)
				(type default)
			)
			(layer "F.SilkS")
		)
		(fp_line
			(start -0.7874 0.4064)
			(end -0.7874 -0.4064)
			(stroke
				(width 0.1524)
				(type default)
			)
			(layer "F.SilkS")
		)
		(fp_line
			(start 0.7874 -0.4064)
			(end 0.7874 0.4064)
			(stroke
				(width 0.1524)
				(type default)
			)
			(layer "F.SilkS")
		)
		(fp_line
			(start 0.7874 0.4064)
			(end -0.7874 0.4064)
			(stroke
				(width 0.1524)
				(type default)
			)
			(layer "F.SilkS")
		)
		(fp_line
			(start -0.67945 -0.305054)
			(end -0.12065 -0.305054)
			(stroke
				(width 0.1)
				(type default)
			)
			(layer "F.Fab")
		)
		(fp_line
			(start -0.67945 0.3048)
			(end -0.67945 -0.305054)
			(stroke
				(width 0.1)
				(type default)
			)
			(layer "F.Fab")
		)
		(fp_line
			(start -0.12065 -0.305054)
			(end -0.12065 -0.2794)
			(stroke
				(width 0.1)
				(type default)
			)
			(layer "F.Fab")
		)
		(fp_line
			(start -0.12065 -0.2794)
			(end 0.12065 -0.2794)
			(stroke
				(width 0.1)
				(type default)
			)
			(layer "F.Fab")
		)
		(fp_line
			(start -0.12065 0.2794)
			(end -0.12065 0.3048)
			(stroke
				(width 0.1)
				(type default)
			)
			(layer "F.Fab")
		)
		(fp_line
			(start -0.12065 0.3048)
			(end -0.67945 0.3048)
			(stroke
				(width 0.1)
				(type default)
			)
			(layer "F.Fab")
		)
		(fp_line
			(start 0.120396 0.2794)
			(end -0.12065 0.2794)
			(stroke
				(width 0.1)
				(type default)
			)
			(layer "F.Fab")
		)
		(fp_line
			(start 0.120396 0.3048)
			(end 0.120396 0.2794)
			(stroke
				(width 0.1)
				(type default)
			)
			(layer "F.Fab")
		)
		(fp_line
			(start 0.12065 -0.3048)
			(end 0.67945 -0.3048)
			(stroke
				(width 0.1)
				(type default)
			)
			(layer "F.Fab")
		)
		(fp_line
			(start 0.12065 -0.2794)
			(end 0.12065 -0.3048)
			(stroke
				(width 0.1)
				(type default)
			)
			(layer "F.Fab")
		)
		(fp_line
			(start 0.67945 -0.3048)
			(end 0.67945 0.3048)
			(stroke
				(width 0.1)
				(type default)
			)
			(layer "F.Fab")
		)
		(fp_line
			(start 0.67945 0.3048)
			(end 0.120396 0.3048)
			(stroke
				(width 0.1)
				(type default)
			)
			(layer "F.Fab")
		)
		(pad "1" smd circle
			(at -0.40005 0)
			(size 0 0)
			(layers "F.Cu" "F.Mask" "F.Paste")
			(net "SSD12_ADC_A0")
		)
		(pad "2" smd circle
			(at 0.40005 0)
			(size 0 0)
			(layers "F.Cu" "F.Mask" "F.Paste")
			(net "P3V3_AUX")
		)
	)
	(footprint ""
		(layer "F.Cu")
		(at 316.908942 -26.03373)
		(property "Reference" "R4074"
			(at 0 0 0)
			(layer "F.SilkS")
			(hide yes)
			(effects
				(font
					(size 1.27 1.27)
				)
			)
		)
		(property "Value" ""
			(at 0 0 0)
			(layer "F.Fab")
			(effects
				(font
					(size 1.27 1.27)
				)
			)
		)
		(duplicate_pad_numbers_are_jumpers no)
		(fp_line
			(start -0.7874 -0.4064)
			(end 0.7874 -0.4064)
			(stroke
				(width 0.1524)
				(type default)
			)
			(layer "F.SilkS")
		)
		(fp_line
			(start -0.7874 0.4064)
			(end -0.7874 -0.4064)
			(stroke
				(width 0.1524)
				(type default)
			)
			(layer "F.SilkS")
		)
		(fp_line
			(start 0.7874 -0.4064)
			(end 0.7874 0.4064)
			(stroke
				(width 0.1524)
				(type default)
			)
			(layer "F.SilkS")
		)
		(fp_line
			(start 0.7874 0.4064)
			(end -0.7874 0.4064)
			(stroke
				(width 0.1524)
				(type default)
			)
			(layer "F.SilkS")
		)
		(fp_line
			(start -0.67945 -0.305054)
			(end -0.12065 -0.305054)
			(stroke
				(width 0.1)
				(type default)
			)
			(layer "F.Fab")
		)
		(fp_line
			(start -0.67945 0.3048)
			(end -0.67945 -0.305054)
			(stroke
				(width 0.1)
				(type default)
			)
			(layer "F.Fab")
		)
		(fp_line
			(start -0.12065 -0.305054)
			(end -0.12065 -0.2794)
			(stroke
				(width 0.1)
				(type default)
			)
			(layer "F.Fab")
		)
		(fp_line
			(start -0.12065 -0.2794)
			(end 0.12065 -0.2794)
			(stroke
				(width 0.1)
				(type default)
			)
			(layer "F.Fab")
		)
		(fp_line
			(start -0.12065 0.2794)
			(end -0.12065 0.3048)
			(stroke
				(width 0.1)
				(type default)
			)
			(layer "F.Fab")
		)
		(fp_line
			(start -0.12065 0.3048)
			(end -0.67945 0.3048)
			(stroke
				(width 0.1)
				(type default)
			)
			(layer "F.Fab")
		)
		(fp_line
			(start 0.120396 0.2794)
			(end -0.12065 0.2794)
			(stroke
				(width 0.1)
				(type default)
			)
			(layer "F.Fab")
		)
		(fp_line
			(start 0.120396 0.3048)
			(end 0.120396 0.2794)
			(stroke
				(width 0.1)
				(type default)
			)
			(layer "F.Fab")
		)
		(fp_line
			(start 0.12065 -0.3048)
			(end 0.67945 -0.3048)
			(stroke
				(width 0.1)
				(type default)
			)
			(layer "F.Fab")
		)
		(fp_line
			(start 0.12065 -0.2794)
			(end 0.12065 -0.3048)
			(stroke
				(width 0.1)
				(type default)
			)
			(layer "F.Fab")
		)
		(fp_line
			(start 0.67945 -0.3048)
			(end 0.67945 0.3048)
			(stroke
				(width 0.1)
				(type default)
			)
			(layer "F.Fab")
		)
		(fp_line
			(start 0.67945 0.3048)
			(end 0.120396 0.3048)
			(stroke
				(width 0.1)
				(type default)
			)
			(layer "F.Fab")
		)
		(pad "1" smd circle
			(at -0.40005 0)
			(size 0 0)
			(layers "F.Cu" "F.Mask" "F.Paste")
			(net "P3V3_AUX")
		)
		(pad "2" smd circle
			(at 0.40005 0)
			(size 0 0)
			(layers "F.Cu" "F.Mask" "F.Paste")
			(net "PRSNT_SSD11_R_N")
		)
	)
	(footprint ""
		(layer "F.Cu")
		(at 175.0949 -104.830372 180)
		(property "Reference" "R173"
			(at 0 0 180)
			(layer "F.SilkS")
			(hide yes)
			(effects
				(font
					(size 1.27 1.27)
				)
			)
		)
		(property "Value" ""
			(at 0 0 180)
			(layer "F.Fab")
			(effects
				(font
					(size 1.27 1.27)
				)
			)
		)
		(duplicate_pad_numbers_are_jumpers no)
		(fp_line
			(start 0.7874 0.4064)
			(end -0.7874 0.4064)
			(stroke
				(width 0.1524)
				(type default)
			)
			(layer "F.SilkS")
		)
		(fp_line
			(start 0.7874 -0.4064)
			(end 0.7874 0.4064)
			(stroke
				(width 0.1524)
				(type default)
			)
			(layer "F.SilkS")
		)
		(fp_line
			(start -0.7874 0.4064)
			(end -0.7874 -0.4064)
			(stroke
				(width 0.1524)
				(type default)
			)
			(layer "F.SilkS")
		)
		(fp_line
			(start -0.7874 -0.4064)
			(end 0.7874 -0.4064)
			(stroke
				(width 0.1524)
				(type default)
			)
			(layer "F.SilkS")
		)
		(fp_line
			(start 0.67945 0.3048)
			(end 0.120396 0.3048)
			(stroke
				(width 0.1)
				(type default)
			)
			(layer "F.Fab")
		)
		(fp_line
			(start 0.67945 -0.3048)
			(end 0.67945 0.3048)
			(stroke
				(width 0.1)
				(type default)
			)
			(layer "F.Fab")
		)
		(fp_line
			(start 0.12065 -0.2794)
			(end 0.12065 -0.3048)
			(stroke
				(width 0.1)
				(type default)
			)
			(layer "F.Fab")
		)
		(fp_line
			(start 0.12065 -0.3048)
			(end 0.67945 -0.3048)
			(stroke
				(width 0.1)
				(type default)
			)
			(layer "F.Fab")
		)
		(fp_line
			(start 0.120396 0.3048)
			(end 0.120396 0.2794)
			(stroke
				(width 0.1)
				(type default)
			)
			(layer "F.Fab")
		)
		(fp_line
			(start 0.120396 0.2794)
			(end -0.12065 0.2794)
			(stroke
				(width 0.1)
				(type default)
			)
			(layer "F.Fab")
		)
		(fp_line
			(start -0.12065 0.3048)
			(end -0.67945 0.3048)
			(stroke
				(width 0.1)
				(type default)
			)
			(layer "F.Fab")
		)
		(fp_line
			(start -0.12065 0.2794)
			(end -0.12065 0.3048)
			(stroke
				(width 0.1)
				(type default)
			)
			(layer "F.Fab")
		)
		(fp_line
			(start -0.12065 -0.2794)
			(end 0.12065 -0.2794)
			(stroke
				(width 0.1)
				(type default)
			)
			(layer "F.Fab")
		)
		(fp_line
			(start -0.12065 -0.305054)
			(end -0.12065 -0.2794)
			(stroke
				(width 0.1)
				(type default)
			)
			(layer "F.Fab")
		)
		(fp_line
			(start -0.67945 0.3048)
			(end -0.67945 -0.305054)
			(stroke
				(width 0.1)
				(type default)
			)
			(layer "F.Fab")
		)
		(fp_line
			(start -0.67945 -0.305054)
			(end -0.12065 -0.305054)
			(stroke
				(width 0.1)
				(type default)
			)
			(layer "F.Fab")
		)
		(pad "1" smd circle
			(at -0.40005 0 180)
			(size 0 0)
			(layers "F.Cu" "F.Mask" "F.Paste")
			(net "CLK_50M_NIC3_RBT_REF")
		)
		(pad "2" smd circle
			(at 0.40005 0 180)
			(size 0 0)
			(layers "F.Cu" "F.Mask" "F.Paste")
			(net "GND")
		)
	)
)
